FILE_TYPE = CONNECTIVITY;
{Allegro Design Entry HDL 17.2-2016 S081 (4005846) 1/11/2022}
"PAGE_NUMBER" = 129;
0"NC";
END.
